# BASEBOARD_FAB2 (Tioga Pass) — schematic netlist excerpt (pin names and nets, part order shuffled) for the footprints in the layout excerpt that follows; sources: Cadence DE-HDL packaged netlist, KiCad conversion of Wiwynn_Tioga_Pass_MB.brd

C6A5  CAPP  470UF 2.5V 20% ALUM  pkg 3018  page 220 : A = PVDDQ_DEF ; B = GND
R1W15  RES  0.0 5% CHIP  pkg 0402  page 115 : A = USB2_PCH_BMC_P5_DN_R ; B = USB2_PCH_BMC_P5_DN
R7D10  RES  10.0K 1% CHIP  pkg 0402  page 133 : A = P3V3_STBY ; B = PU_LPC_PME_N

(kicad_pcb
	(version 20260206)
	(generator "pcbnew")
	(generator_version "10.0")
	(general
		(thickness 1.6)
		(legacy_teardrops no)
	)
	(paper "A4")
	(title_block
		(title "Wiwynn_Tioga_Pass_MB.brd")
		(comment 1 "Tioga Pass / footprints 1075-1077 of 4770")
	)
	(layers
		(0 "F.Cu" signal "TOP")
		(4 "In1.Cu" signal "L2GND")
		(6 "In2.Cu" signal "L3")
		(8 "In3.Cu" signal "L4GND")
		(10 "In4.Cu" signal "L5")
		(12 "In5.Cu" signal "L6GND")
		(14 "In6.Cu" signal "L7VCC")
		(16 "In7.Cu" signal "L8VCC")
		(18 "In8.Cu" signal "L9GND")
		(20 "In9.Cu" signal "L10")
		(22 "In10.Cu" signal "L11GND")
		(24 "In11.Cu" signal "L12")
		(26 "In12.Cu" signal "L13GND")
		(2 "B.Cu" signal "BOTTOM")
		(9 "F.Adhes" user "F.Adhesive")
		(11 "B.Adhes" user "B.Adhesive")
		(13 "F.Paste" user "Package Geometry/Pastemask Top")
		(15 "B.Paste" user "Package Geometry/Pastemask Bottom")
		(5 "F.SilkS" user "Ref Des/Silkscreen Top")
		(7 "B.SilkS" user "Ref Des/Silkscreen Bottom")
		(1 "F.Mask" user "Board Geometry/Soldermask Top")
		(3 "B.Mask" user "Board Geometry/Soldermask Bottom")
		(17 "Dwgs.User" user "User.Drawings")
		(19 "Cmts.User" user "User.Comments")
		(21 "Eco1.User" user "User.Eco1")
		(23 "Eco2.User" user "User.Eco2")
		(25 "Edge.Cuts" user "Board Geometry/Outline")
		(27 "Margin" user)
		(31 "F.CrtYd" user "Package Geometry/Place Bound Top")
		(29 "B.CrtYd" user "Package Geometry/Place Bound Bottom")
		(35 "F.Fab" user "Ref Des/Assembly Top")
		(33 "B.Fab" user "Ref Des/Assembly Bottom")
	)
	(footprint ""
		(layer "F.Cu")
		(at 384.556 -87.3125 180)
		(property "Reference" "R7D10"
			(at 0 0 180)
			(layer "F.SilkS")
			(hide yes)
			(effects
				(font
					(size 1.27 1.27)
				)
			)
		)
		(property "Value" ""
			(at 0 0 180)
			(layer "F.Fab")
			(effects
				(font
					(size 1.27 1.27)
				)
			)
		)
		(duplicate_pad_numbers_are_jumpers no)
		(fp_poly
			(pts
				(xy -0.2794 -0.1016) (xy 0.2794 -0.1016) (xy 0.2794 0.9906) (xy -0.2794 0.9906)
			)
			(stroke
				(width 0)
				(type default)
			)
			(fill no)
			(layer "F.CrtYd")
		)
		(fp_line
			(start 0.2794 0.9906)
			(end 0.2794 -0.1016)
			(stroke
				(width 0.1)
				(type default)
			)
			(layer "F.Fab")
		)
		(fp_line
			(start 0.2794 -0.1016)
			(end -0.2794 -0.1016)
			(stroke
				(width 0.1)
				(type default)
			)
			(layer "F.Fab")
		)
		(fp_line
			(start -0.2794 0.9906)
			(end 0.2794 0.9906)
			(stroke
				(width 0.1)
				(type default)
			)
			(layer "F.Fab")
		)
		(fp_line
			(start -0.2794 -0.1016)
			(end -0.2794 0.9906)
			(stroke
				(width 0.1)
				(type default)
			)
			(layer "F.Fab")
		)
		(pad "1" smd rect
			(at 0 0 180)
			(size 0.508 0.508)
			(layers "F.Cu" "F.Mask" "F.Paste")
			(net "P3V3_STBY")
		)
		(pad "2" smd rect
			(at 0 0.889 180)
			(size 0.508 0.508)
			(layers "F.Cu" "F.Mask" "F.Paste")
			(net "PU_LPC_PME_N")
		)
		(zone
			(layer "F.Cu")
			(hatch none 0.5)
			(connect_pads
				(clearance 0)
			)
			(min_thickness 0.25)
			(keepout
				(tracks not_allowed)
				(vias allowed)
				(pads allowed)
				(copperpour not_allowed)
				(footprints allowed)
			)
			(placement
				(enabled no)
				(sheetname "")
			)
			(fill
				(thermal_gap 0.5)
				(thermal_bridge_width 0.5)
				(island_removal_mode 0)
			)
			(polygon
				(pts
					(xy 384.81 -87.9475) (xy 384.302 -87.9475) (xy 384.302 -87.5665) (xy 384.81 -87.5665)
				)
			)
		)
		(zone
			(layer "F.Cu")
			(hatch none 0.5)
			(connect_pads
				(clearance 0)
			)
			(min_thickness 0.25)
			(keepout
				(tracks allowed)
				(vias not_allowed)
				(pads allowed)
				(copperpour not_allowed)
				(footprints allowed)
			)
			(placement
				(enabled no)
				(sheetname "")
			)
			(fill
				(thermal_gap 0.5)
				(thermal_bridge_width 0.5)
				(island_removal_mode 0)
			)
			(polygon
				(pts
					(xy 384.81 -87.5665) (xy 384.302 -87.5665) (xy 384.302 -87.9475) (xy 384.81 -87.9475)
				)
			)
		)
	)
	(footprint ""
		(layer "F.Cu")
		(at 408.319478 -118.239032 90)
		(property "Reference" "R1W15"
			(at -0.8382 -0.67818 90)
			(unlocked yes)
			(layer "F.SilkS")
			(effects
				(font
					(size 0.4064 0.254)
					(thickness 0.1524)
				)
				(justify left)
			)
		)
		(property "Value" ""
			(at 0 0 90)
			(layer "F.Fab")
			(effects
				(font
					(size 1.27 1.27)
				)
			)
		)
		(duplicate_pad_numbers_are_jumpers no)
		(fp_poly
			(pts
				(xy -0.2794 -0.1016) (xy 0.2794 -0.1016) (xy 0.2794 0.9906) (xy -0.2794 0.9906)
			)
			(stroke
				(width 0)
				(type default)
			)
			(fill no)
			(layer "F.CrtYd")
		)
		(fp_line
			(start 0.2794 -0.1016)
			(end -0.2794 -0.1016)
			(stroke
				(width 0.1)
				(type default)
			)
			(layer "F.Fab")
		)
		(fp_line
			(start -0.2794 -0.1016)
			(end -0.2794 0.9906)
			(stroke
				(width 0.1)
				(type default)
			)
			(layer "F.Fab")
		)
		(fp_line
			(start 0.2794 0.9906)
			(end 0.2794 -0.1016)
			(stroke
				(width 0.1)
				(type default)
			)
			(layer "F.Fab")
		)
		(fp_line
			(start -0.2794 0.9906)
			(end 0.2794 0.9906)
			(stroke
				(width 0.1)
				(type default)
			)
			(layer "F.Fab")
		)
		(pad "1" smd rect
			(at 0 0 90)
			(size 0.508 0.508)
			(layers "F.Cu" "F.Mask" "F.Paste")
			(net "USB2_PCH_BMC_P5_DN_R")
		)
		(pad "2" smd rect
			(at 0 0.889 90)
			(size 0.508 0.508)
			(layers "F.Cu" "F.Mask" "F.Paste")
			(net "USB2_PCH_BMC_P5_DN")
		)
		(zone
			(layer "F.Cu")
			(hatch none 0.5)
			(connect_pads
				(clearance 0)
			)
			(min_thickness 0.25)
			(keepout
				(tracks allowed)
				(vias not_allowed)
				(pads allowed)
				(copperpour not_allowed)
				(footprints allowed)
			)
			(placement
				(enabled no)
				(sheetname "")
			)
			(fill
				(thermal_gap 0.5)
				(thermal_bridge_width 0.5)
				(island_removal_mode 0)
			)
			(polygon
				(pts
					(xy 408.573478 -117.985032) (xy 408.573478 -118.493032) (xy 408.954478 -118.493032) (xy 408.954478 -117.985032)
				)
			)
		)
		(zone
			(layer "F.Cu")
			(hatch none 0.5)
			(connect_pads
				(clearance 0)
			)
			(min_thickness 0.25)
			(keepout
				(tracks not_allowed)
				(vias allowed)
				(pads allowed)
				(copperpour not_allowed)
				(footprints allowed)
			)
			(placement
				(enabled no)
				(sheetname "")
			)
			(fill
				(thermal_gap 0.5)
				(thermal_bridge_width 0.5)
				(island_removal_mode 0)
			)
			(polygon
				(pts
					(xy 408.954478 -117.985032) (xy 408.954478 -118.493032) (xy 408.573478 -118.493032) (xy 408.573478 -117.985032)
				)
			)
		)
	)
	(footprint ""
		(layer "F.Cu")
		(at 332.5114 -140.9446 90)
		(property "Reference" "C6A5"
			(at 2.92862 3.24612 0)
			(unlocked yes)
			(layer "F.SilkS")
			(effects
				(font
					(size 0.4064 0.254)
					(thickness 0.1524)
				)
			)
		)
		(property "Value" ""
			(at 0 0 90)
			(layer "F.Fab")
			(effects
				(font
					(size 1.27 1.27)
				)
			)
		)
		(duplicate_pad_numbers_are_jumpers no)
		(fp_line
			(start 2.504948 -1.616456)
			(end 2.504948 1.633728)
			(stroke
				(width 0.1524)
				(type default)
			)
			(layer "F.SilkS")
		)
		(fp_line
			(start 1.6002 -1.616456)
			(end 2.504948 -1.616456)
			(stroke
				(width 0.1524)
				(type default)
			)
			(layer "F.SilkS")
		)
		(fp_line
			(start -1.6002 -1.616456)
			(end -2.563114 -1.616456)
			(stroke
				(width 0.1524)
				(type default)
			)
			(layer "F.SilkS")
		)
		(fp_line
			(start -2.563114 -1.616456)
			(end -2.563114 1.633728)
			(stroke
				(width 0.1524)
				(type default)
			)
			(layer "F.SilkS")
		)
		(fp_line
			(start 2.504948 1.633728)
			(end 1.6002 1.633728)
			(stroke
				(width 0.1524)
				(type default)
			)
			(layer "F.SilkS")
		)
		(fp_line
			(start -2.563114 1.633728)
			(end -1.6002 1.633728)
			(stroke
				(width 0.1524)
				(type default)
			)
			(layer "F.SilkS")
		)
		(fp_line
			(start 2.286 7.366)
			(end 2.286 1.63195)
			(stroke
				(width 0.1524)
				(type default)
			)
			(layer "F.SilkS")
		)
		(fp_line
			(start 2.286 7.366)
			(end 1.600708 7.366)
			(stroke
				(width 0.1524)
				(type default)
			)
			(layer "F.SilkS")
		)
		(fp_line
			(start -2.286 7.366)
			(end -2.286 1.632712)
			(stroke
				(width 0.1524)
				(type default)
			)
			(layer "F.SilkS")
		)
		(fp_line
			(start -2.286 7.366)
			(end -1.60147 7.366)
			(stroke
				(width 0.1524)
				(type default)
			)
			(layer "F.SilkS")
		)
		(fp_rect
			(start -2.286 7.366)
			(end 2.286 -0.254)
			(stroke
				(width 0)
				(type default)
			)
			(fill no)
			(layer "F.CrtYd")
		)
		(fp_line
			(start 2.286 -0.254)
			(end 2.286 7.366)
			(stroke
				(width 0.1)
				(type default)
			)
			(layer "F.Fab")
		)
		(fp_line
			(start -2.286 -0.254)
			(end 2.286 -0.254)
			(stroke
				(width 0.1)
				(type default)
			)
			(layer "F.Fab")
		)
		(fp_line
			(start 2.286 7.366)
			(end -2.286 7.366)
			(stroke
				(width 0.1)
				(type default)
			)
			(layer "F.Fab")
		)
		(fp_line
			(start -2.286 7.366)
			(end -2.286 -0.254)
			(stroke
				(width 0.1)
				(type default)
			)
			(layer "F.Fab")
		)
		(pad "1" smd rect
			(at 0 0 90)
			(size 2.54 3.048)
			(layers "F.Cu" "F.Mask" "F.Paste")
			(net "PVDDQ_DEF")
		)
		(pad "2" smd rect
			(at 0 7.112 90)
			(size 2.54 3.048)
			(layers "F.Cu" "F.Mask" "F.Paste")
			(net "GND")
		)
	)
)
